# S9S_MB_2U (Grand Teton) — schematic netlist excerpt (pin names and nets, part order shuffled) for the footprints in the layout excerpt that follows; sources: Cadence DE-HDL packaged netlist, KiCad conversion of 03242023_DA0F0TMBIJ0_F0T_Motherboard_J_brd_V01_OCP.brd

R92  Q_RES  240 1% EMPTY  pkg 0402LF  page 126 : A = PVNN_TERM_CPU1 ; B = PU_CPU1_UPI2_AC_COUPLING
C1250  Q_CAP  1UF 6.3V 10% EMPTY  pkg 0402  page 189 : A = P1V05_PCH_AUX ; B = GND

(kicad_pcb
	(version 20260206)
	(generator "pcbnew")
	(generator_version "10.0")
	(general
		(thickness 1.6)
		(legacy_teardrops no)
	)
	(paper "A4")
	(title_block
		(title "03242023_DA0F0TMBIJ0_F0T_Motherboard_J_brd_V01_OCP.brd")
		(comment 1 "Grand Teton / footprints 4735-4736 of 6105")
	)
	(layers
		(0 "F.Cu" signal "TOP")
		(4 "In1.Cu" signal "GND")
		(6 "In2.Cu" signal "IN1")
		(8 "In3.Cu" signal "GND1")
		(10 "In4.Cu" signal "IN2")
		(12 "In5.Cu" signal "GND2")
		(14 "In6.Cu" signal "IN3")
		(16 "In7.Cu" signal "GND3")
		(18 "In8.Cu" signal "VCC")
		(20 "In9.Cu" signal "VCC1")
		(22 "In10.Cu" signal "GND4")
		(24 "In11.Cu" signal "IN4")
		(26 "In12.Cu" signal "GND5")
		(28 "In13.Cu" signal "IN5")
		(30 "In14.Cu" signal "GND6")
		(32 "In15.Cu" signal "IN6")
		(34 "In16.Cu" signal "GND7")
		(2 "B.Cu" signal "BOTTOM")
		(9 "F.Adhes" user "F.Adhesive")
		(11 "B.Adhes" user "B.Adhesive")
		(13 "F.Paste" user "Package Geometry/Pastemask Top")
		(15 "B.Paste" user "Package Geometry/Pastemask Bottom")
		(5 "F.SilkS" user "Ref Des/Silkscreen Top")
		(7 "B.SilkS" user "Ref Des/Silkscreen Bottom")
		(1 "F.Mask" user "Board Geometry/Soldermask Top")
		(3 "B.Mask" user "Board Geometry/Soldermask Bottom")
		(17 "Dwgs.User" user "User.Drawings")
		(19 "Cmts.User" user "User.Comments")
		(21 "Eco1.User" user "User.Eco1")
		(23 "Eco2.User" user "User.Eco2")
		(25 "Edge.Cuts" user "Board Geometry/Outline")
		(27 "Margin" user)
		(31 "F.CrtYd" user "Package Geometry/Place Bound Top")
		(29 "B.CrtYd" user "Package Geometry/Place Bound Bottom")
		(35 "F.Fab" user "Ref Des/Assembly Top")
		(33 "B.Fab" user "Ref Des/Assembly Bottom")
	)
	(footprint ""
		(layer "B.Cu")
		(at 53.746908 -193.25971 -90)
		(property "Reference" "R92"
			(at 0 0 90)
			(layer "B.SilkS")
			(hide yes)
			(effects
				(font
					(size 1.27 1.27)
				)
				(justify mirror)
			)
		)
		(property "Value" ""
			(at 0 0 90)
			(layer "B.Fab")
			(effects
				(font
					(size 1.27 1.27)
				)
				(justify mirror)
			)
		)
		(duplicate_pad_numbers_are_jumpers no)
		(fp_line
			(start -0.7874 0.4064)
			(end 0.7874 0.4064)
			(stroke
				(width 0.1524)
				(type default)
			)
			(layer "B.SilkS")
		)
		(fp_line
			(start 0.7874 0.4064)
			(end 0.7874 -0.4064)
			(stroke
				(width 0.1524)
				(type default)
			)
			(layer "B.SilkS")
		)
		(fp_line
			(start -0.7874 -0.4064)
			(end -0.7874 0.4064)
			(stroke
				(width 0.1524)
				(type default)
			)
			(layer "B.SilkS")
		)
		(fp_line
			(start 0.7874 -0.4064)
			(end -0.7874 -0.4064)
			(stroke
				(width 0.1524)
				(type default)
			)
			(layer "B.SilkS")
		)
		(fp_line
			(start -0.67945 0.3048)
			(end -0.120396 0.3048)
			(stroke
				(width 0.1)
				(type default)
			)
			(layer "B.Fab")
		)
		(fp_line
			(start -0.120396 0.3048)
			(end -0.120396 0.2794)
			(stroke
				(width 0.1)
				(type default)
			)
			(layer "B.Fab")
		)
		(fp_line
			(start 0.12065 0.3048)
			(end 0.67945 0.3048)
			(stroke
				(width 0.1)
				(type default)
			)
			(layer "B.Fab")
		)
		(fp_line
			(start 0.67945 0.3048)
			(end 0.67945 -0.305054)
			(stroke
				(width 0.1)
				(type default)
			)
			(layer "B.Fab")
		)
		(fp_line
			(start -0.120396 0.2794)
			(end 0.12065 0.2794)
			(stroke
				(width 0.1)
				(type default)
			)
			(layer "B.Fab")
		)
		(fp_line
			(start 0.12065 0.2794)
			(end 0.12065 0.3048)
			(stroke
				(width 0.1)
				(type default)
			)
			(layer "B.Fab")
		)
		(fp_line
			(start -0.12065 -0.2794)
			(end -0.12065 -0.3048)
			(stroke
				(width 0.1)
				(type default)
			)
			(layer "B.Fab")
		)
		(fp_line
			(start 0.12065 -0.2794)
			(end -0.12065 -0.2794)
			(stroke
				(width 0.1)
				(type default)
			)
			(layer "B.Fab")
		)
		(fp_line
			(start -0.67945 -0.3048)
			(end -0.67945 0.3048)
			(stroke
				(width 0.1)
				(type default)
			)
			(layer "B.Fab")
		)
		(fp_line
			(start -0.12065 -0.3048)
			(end -0.67945 -0.3048)
			(stroke
				(width 0.1)
				(type default)
			)
			(layer "B.Fab")
		)
		(fp_line
			(start 0.12065 -0.305054)
			(end 0.12065 -0.2794)
			(stroke
				(width 0.1)
				(type default)
			)
			(layer "B.Fab")
		)
		(fp_line
			(start 0.67945 -0.305054)
			(end 0.12065 -0.305054)
			(stroke
				(width 0.1)
				(type default)
			)
			(layer "B.Fab")
		)
		(pad "1" smd circle
			(at 0.40005 0 90)
			(size 0 0)
			(layers "B.Cu" "B.Mask" "B.Paste")
			(net "PVNN_TERM_CPU1")
		)
		(pad "2" smd circle
			(at -0.40005 0 90)
			(size 0 0)
			(layers "B.Cu" "B.Mask" "B.Paste")
			(net "PU_CPU1_UPI2_AC_COUPLING")
		)
	)
	(footprint ""
		(layer "B.Cu")
		(at 326.743822 -70.207378)
		(property "Reference" "C1250"
			(at 0 0 0)
			(layer "B.SilkS")
			(hide yes)
			(effects
				(font
					(size 1.27 1.27)
				)
				(justify mirror)
			)
		)
		(property "Value" ""
			(at 0 0 0)
			(layer "B.Fab")
			(effects
				(font
					(size 1.27 1.27)
				)
				(justify mirror)
			)
		)
		(duplicate_pad_numbers_are_jumpers no)
		(fp_line
			(start -0.7874 -0.4064)
			(end -0.7874 0.4064)
			(stroke
				(width 0.1524)
				(type default)
			)
			(layer "B.SilkS")
		)
		(fp_line
			(start -0.7874 0.4064)
			(end 0.7874 0.4064)
			(stroke
				(width 0.1524)
				(type default)
			)
			(layer "B.SilkS")
		)
		(fp_line
			(start 0.7874 -0.4064)
			(end -0.7874 -0.4064)
			(stroke
				(width 0.1524)
				(type default)
			)
			(layer "B.SilkS")
		)
		(fp_line
			(start 0.7874 0.4064)
			(end 0.7874 -0.4064)
			(stroke
				(width 0.1524)
				(type default)
			)
			(layer "B.SilkS")
		)
		(fp_line
			(start -0.67945 -0.3048)
			(end -0.67945 0.3048)
			(stroke
				(width 0.1)
				(type default)
			)
			(layer "B.Fab")
		)
		(fp_line
			(start -0.67945 0.3048)
			(end -0.120396 0.3048)
			(stroke
				(width 0.1)
				(type default)
			)
			(layer "B.Fab")
		)
		(fp_line
			(start -0.12065 -0.3048)
			(end -0.67945 -0.3048)
			(stroke
				(width 0.1)
				(type default)
			)
			(layer "B.Fab")
		)
		(fp_line
			(start -0.12065 -0.2794)
			(end -0.12065 -0.3048)
			(stroke
				(width 0.1)
				(type default)
			)
			(layer "B.Fab")
		)
		(fp_line
			(start -0.120396 0.2794)
			(end 0.12065 0.2794)
			(stroke
				(width 0.1)
				(type default)
			)
			(layer "B.Fab")
		)
		(fp_line
			(start -0.120396 0.3048)
			(end -0.120396 0.2794)
			(stroke
				(width 0.1)
				(type default)
			)
			(layer "B.Fab")
		)
		(fp_line
			(start 0.12065 -0.305054)
			(end 0.12065 -0.2794)
			(stroke
				(width 0.1)
				(type default)
			)
			(layer "B.Fab")
		)
		(fp_line
			(start 0.12065 -0.2794)
			(end -0.12065 -0.2794)
			(stroke
				(width 0.1)
				(type default)
			)
			(layer "B.Fab")
		)
		(fp_line
			(start 0.12065 0.2794)
			(end 0.12065 0.3048)
			(stroke
				(width 0.1)
				(type default)
			)
			(layer "B.Fab")
		)
		(fp_line
			(start 0.12065 0.3048)
			(end 0.67945 0.3048)
			(stroke
				(width 0.1)
				(type default)
			)
			(layer "B.Fab")
		)
		(fp_line
			(start 0.67945 -0.305054)
			(end 0.12065 -0.305054)
			(stroke
				(width 0.1)
				(type default)
			)
			(layer "B.Fab")
		)
		(fp_line
			(start 0.67945 0.3048)
			(end 0.67945 -0.305054)
			(stroke
				(width 0.1)
				(type default)
			)
			(layer "B.Fab")
		)
		(pad "1" smd circle
			(at 0.40005 0 180)
			(size 0 0)
			(layers "B.Cu" "B.Mask" "B.Paste")
			(net "P1V05_PCH_AUX")
		)
		(pad "2" smd circle
			(at -0.40005 0 180)
			(size 0 0)
			(layers "B.Cu" "B.Mask" "B.Paste")
			(net "GND")
		)
	)
)
